# S9S_MB_2U (Grand Teton) — schematic netlist excerpt (pin names and nets, part order shuffled) for the footprints in the layout excerpt that follows; sources: Cadence DE-HDL packaged netlist, KiCad conversion of 03242023_DA0F0TMBIJ0_F0T_Motherboard_J_brd_V01_OCP.brd

U21  NC7SB3157  NC7SB3157P6X IC  pkg SMLF  page 133
  B1  = JTAG_MUX_CPU1_GTL_TDI
  GND  = GND
  B0  = JTAG_MUX_CPU0_GTL_TDI
  A  = JTAG_QS_MUX_GTL_TDI
  VCC  = P3V3_AUX
  S  = FM_CPU0_SKTOCC_N

PR355  Q_RES  2.2 1% CHIP  pkg 0402LF  page 271 : A = PVCCFA_EHV_FIVRA_CPU0_PVCC1 ; B = PVCCFA_EHV_FIVRA_CPU0_VDD1

(kicad_pcb
	(version 20260206)
	(generator "pcbnew")
	(generator_version "10.0")
	(general
		(thickness 1.6)
		(legacy_teardrops no)
	)
	(paper "A4")
	(title_block
		(title "03242023_DA0F0TMBIJ0_F0T_Motherboard_J_brd_V01_OCP.brd")
		(comment 1 "Grand Teton / footprints 5199-5200 of 6105")
	)
	(layers
		(0 "F.Cu" signal "TOP")
		(4 "In1.Cu" signal "GND")
		(6 "In2.Cu" signal "IN1")
		(8 "In3.Cu" signal "GND1")
		(10 "In4.Cu" signal "IN2")
		(12 "In5.Cu" signal "GND2")
		(14 "In6.Cu" signal "IN3")
		(16 "In7.Cu" signal "GND3")
		(18 "In8.Cu" signal "VCC")
		(20 "In9.Cu" signal "VCC1")
		(22 "In10.Cu" signal "GND4")
		(24 "In11.Cu" signal "IN4")
		(26 "In12.Cu" signal "GND5")
		(28 "In13.Cu" signal "IN5")
		(30 "In14.Cu" signal "GND6")
		(32 "In15.Cu" signal "IN6")
		(34 "In16.Cu" signal "GND7")
		(2 "B.Cu" signal "BOTTOM")
		(9 "F.Adhes" user "F.Adhesive")
		(11 "B.Adhes" user "B.Adhesive")
		(13 "F.Paste" user "Package Geometry/Pastemask Top")
		(15 "B.Paste" user "Package Geometry/Pastemask Bottom")
		(5 "F.SilkS" user "Ref Des/Silkscreen Top")
		(7 "B.SilkS" user "Ref Des/Silkscreen Bottom")
		(1 "F.Mask" user "Board Geometry/Soldermask Top")
		(3 "B.Mask" user "Board Geometry/Soldermask Bottom")
		(17 "Dwgs.User" user "User.Drawings")
		(19 "Cmts.User" user "User.Comments")
		(21 "Eco1.User" user "User.Eco1")
		(23 "Eco2.User" user "User.Eco2")
		(25 "Edge.Cuts" user "Board Geometry/Outline")
		(27 "Margin" user)
		(31 "F.CrtYd" user "Package Geometry/Place Bound Top")
		(29 "B.CrtYd" user "Package Geometry/Place Bound Bottom")
		(35 "F.Fab" user "Ref Des/Assembly Top")
		(33 "B.Fab" user "Ref Des/Assembly Bottom")
	)
	(footprint ""
		(layer "B.Cu")
		(at 413.6644 -363.125258 -90)
		(property "Reference" "PR355"
			(at 0 0 90)
			(layer "B.SilkS")
			(hide yes)
			(effects
				(font
					(size 1.27 1.27)
				)
				(justify mirror)
			)
		)
		(property "Value" ""
			(at 0 0 90)
			(layer "B.Fab")
			(effects
				(font
					(size 1.27 1.27)
				)
				(justify mirror)
			)
		)
		(duplicate_pad_numbers_are_jumpers no)
		(fp_line
			(start -0.7874 0.4064)
			(end 0.7874 0.4064)
			(stroke
				(width 0.1524)
				(type default)
			)
			(layer "B.SilkS")
		)
		(fp_line
			(start 0.7874 0.4064)
			(end 0.7874 -0.4064)
			(stroke
				(width 0.1524)
				(type default)
			)
			(layer "B.SilkS")
		)
		(fp_line
			(start -0.7874 -0.4064)
			(end -0.7874 0.4064)
			(stroke
				(width 0.1524)
				(type default)
			)
			(layer "B.SilkS")
		)
		(fp_line
			(start 0.7874 -0.4064)
			(end -0.7874 -0.4064)
			(stroke
				(width 0.1524)
				(type default)
			)
			(layer "B.SilkS")
		)
		(fp_line
			(start -0.67945 0.3048)
			(end -0.120396 0.3048)
			(stroke
				(width 0.1)
				(type default)
			)
			(layer "B.Fab")
		)
		(fp_line
			(start -0.120396 0.3048)
			(end -0.120396 0.2794)
			(stroke
				(width 0.1)
				(type default)
			)
			(layer "B.Fab")
		)
		(fp_line
			(start 0.12065 0.3048)
			(end 0.67945 0.3048)
			(stroke
				(width 0.1)
				(type default)
			)
			(layer "B.Fab")
		)
		(fp_line
			(start 0.67945 0.3048)
			(end 0.67945 -0.305054)
			(stroke
				(width 0.1)
				(type default)
			)
			(layer "B.Fab")
		)
		(fp_line
			(start -0.120396 0.2794)
			(end 0.12065 0.2794)
			(stroke
				(width 0.1)
				(type default)
			)
			(layer "B.Fab")
		)
		(fp_line
			(start 0.12065 0.2794)
			(end 0.12065 0.3048)
			(stroke
				(width 0.1)
				(type default)
			)
			(layer "B.Fab")
		)
		(fp_line
			(start -0.12065 -0.2794)
			(end -0.12065 -0.3048)
			(stroke
				(width 0.1)
				(type default)
			)
			(layer "B.Fab")
		)
		(fp_line
			(start 0.12065 -0.2794)
			(end -0.12065 -0.2794)
			(stroke
				(width 0.1)
				(type default)
			)
			(layer "B.Fab")
		)
		(fp_line
			(start -0.67945 -0.3048)
			(end -0.67945 0.3048)
			(stroke
				(width 0.1)
				(type default)
			)
			(layer "B.Fab")
		)
		(fp_line
			(start -0.12065 -0.3048)
			(end -0.67945 -0.3048)
			(stroke
				(width 0.1)
				(type default)
			)
			(layer "B.Fab")
		)
		(fp_line
			(start 0.12065 -0.305054)
			(end 0.12065 -0.2794)
			(stroke
				(width 0.1)
				(type default)
			)
			(layer "B.Fab")
		)
		(fp_line
			(start 0.67945 -0.305054)
			(end 0.12065 -0.305054)
			(stroke
				(width 0.1)
				(type default)
			)
			(layer "B.Fab")
		)
		(pad "1" smd circle
			(at 0.40005 0 90)
			(size 0 0)
			(layers "B.Cu" "B.Mask" "B.Paste")
			(net "PVCCFA_EHV_FIVRA_CPU0_PVCC1")
		)
		(pad "2" smd circle
			(at -0.40005 0 90)
			(size 0 0)
			(layers "B.Cu" "B.Mask" "B.Paste")
			(net "PVCCFA_EHV_FIVRA_CPU0_VDD1")
		)
	)
	(footprint ""
		(layer "B.Cu")
		(at 206.955898 -193.37401)
		(property "Reference" "U21"
			(at 0.22606 1.93167 0)
			(unlocked yes)
			(layer "B.SilkS")
			(effects
				(font
					(size 0.7874 0.5842)
					(thickness 0.1524)
				)
				(justify mirror)
			)
		)
		(property "Value" ""
			(at 0 0 0)
			(layer "B.Fab")
			(effects
				(font
					(size 1.27 1.27)
				)
				(justify mirror)
			)
		)
		(duplicate_pad_numbers_are_jumpers no)
		(fp_line
			(start -1.7272 -1.1176)
			(end -1.7272 1.1176)
			(stroke
				(width 0.1524)
				(type default)
			)
			(layer "B.SilkS")
		)
		(fp_line
			(start -1.7272 -1.1176)
			(end -0.254 -1.1176)
			(stroke
				(width 0.1524)
				(type default)
			)
			(layer "B.SilkS")
		)
		(fp_line
			(start -1.7272 1.1176)
			(end 1.7272 1.1176)
			(stroke
				(width 0.1524)
				(type default)
			)
			(layer "B.SilkS")
		)
		(fp_line
			(start -0.254 -1.1176)
			(end 0 -0.7366)
			(stroke
				(width 0.1524)
				(type default)
			)
			(layer "B.SilkS")
		)
		(fp_line
			(start 0 -0.7366)
			(end 0.254 -1.1176)
			(stroke
				(width 0.1524)
				(type default)
			)
			(layer "B.SilkS")
		)
		(fp_line
			(start 0.254 -1.1176)
			(end 1.7272 -1.1176)
			(stroke
				(width 0.1524)
				(type default)
			)
			(layer "B.SilkS")
		)
		(fp_line
			(start 1.7272 1.1176)
			(end 1.7272 -1.1176)
			(stroke
				(width 0.1524)
				(type default)
			)
			(layer "B.SilkS")
		)
		(fp_poly
			(pts
				(xy 1.064514 -1.395476) (xy 0.683514 -2.157476) (xy 1.445514 -2.157476)
			)
			(stroke
				(width 0)
				(type default)
			)
			(fill yes)
			(layer "B.SilkS")
		)
		(fp_line
			(start -1.5748 -1.1176)
			(end 1.5748 -1.1176)
			(stroke
				(width 0.1)
				(type default)
			)
			(layer "B.Fab")
		)
		(fp_line
			(start -1.5748 1.1176)
			(end -1.5748 -1.1176)
			(stroke
				(width 0.1)
				(type default)
			)
			(layer "B.Fab")
		)
		(fp_line
			(start 1.5748 -1.1176)
			(end 1.5748 1.1176)
			(stroke
				(width 0.1)
				(type default)
			)
			(layer "B.Fab")
		)
		(fp_line
			(start 1.5748 1.1176)
			(end -1.5748 1.1176)
			(stroke
				(width 0.1)
				(type default)
			)
			(layer "B.Fab")
		)
		(fp_poly
			(pts
				(xy 1.9558 -0.649986) (xy 2.7178 -0.268986) (xy 2.7178 -1.030986)
			)
			(stroke
				(width 0)
				(type default)
			)
			(fill yes)
			(layer "B.Fab")
		)
		(pad "1" smd rect
			(at 0.999998 -0.649986 270)
			(size 0.3556 1.1176)
			(layers "B.Cu" "B.Mask" "B.Paste")
			(net "JTAG_MUX_CPU1_GTL_TDI")
		)
		(pad "2" smd rect
			(at 0.999998 0 270)
			(size 0.3556 1.1176)
			(layers "B.Cu" "B.Mask" "B.Paste")
			(net "GND")
		)
		(pad "3" smd rect
			(at 0.999998 0.649986 270)
			(size 0.3556 1.1176)
			(layers "B.Cu" "B.Mask" "B.Paste")
			(net "JTAG_MUX_CPU0_GTL_TDI")
		)
		(pad "4" smd rect
			(at -0.999998 0.649986 270)
			(size 0.3556 1.1176)
			(layers "B.Cu" "B.Mask" "B.Paste")
			(net "JTAG_QS_MUX_GTL_TDI")
		)
		(pad "5" smd rect
			(at -0.999998 0 270)
			(size 0.3556 1.1176)
			(layers "B.Cu" "B.Mask" "B.Paste")
			(net "P3V3_AUX")
		)
		(pad "6" smd rect
			(at -0.999998 -0.649986 270)
			(size 0.3556 1.1176)
			(layers "B.Cu" "B.Mask" "B.Paste")
			(net "FM_CPU0_SKTOCC_N")
		)
	)
)
